(kicad_pcb
	(version 20260206)
	(generator "pcbnew")
	(generator_version "10.0")
	(general
		(thickness 1.6)
		(legacy_teardrops no)
	)
	(paper "A4")
	(title_block
		(title "12092022_DA0F0TMDCD0_F0T_Management_Board_D_brd_V3_OCP.brd")
		(comment 1 "Grand Teton / footprints 213-218 of 1440")
	)
	(layers
		(0 "F.Cu" signal "TOP")
		(4 "In1.Cu" signal "GND")
		(6 "In2.Cu" signal "IN1")
		(8 "In3.Cu" signal "GND1")
		(10 "In4.Cu" signal "IN2")
		(12 "In5.Cu" signal "VCC")
		(14 "In6.Cu" signal "VCC1")
		(16 "In7.Cu" signal "IN3")
		(18 "In8.Cu" signal "GND2")
		(20 "In9.Cu" signal "IN4")
		(22 "In10.Cu" signal "GND3")
		(2 "B.Cu" signal "BOTTOM")
		(9 "F.Adhes" user "F.Adhesive")
		(11 "B.Adhes" user "B.Adhesive")
		(13 "F.Paste" user "Package Geometry/Pastemask Top")
		(15 "B.Paste" user "Package Geometry/Pastemask Bottom")
		(5 "F.SilkS" user "Ref Des/Silkscreen Top")
		(7 "B.SilkS" user "Ref Des/Silkscreen Bottom")
		(1 "F.Mask" user "Board Geometry/Soldermask Top")
		(3 "B.Mask" user "Board Geometry/Soldermask Bottom")
		(17 "Dwgs.User" user "User.Drawings")
		(19 "Cmts.User" user "User.Comments")
		(21 "Eco1.User" user "User.Eco1")
		(23 "Eco2.User" user "User.Eco2")
		(25 "Edge.Cuts" user "Board Geometry/Outline")
		(27 "Margin" user)
		(31 "F.CrtYd" user "Package Geometry/Place Bound Top")
		(29 "B.CrtYd" user "Package Geometry/Place Bound Bottom")
		(35 "F.Fab" user "Ref Des/Assembly Top")
		(33 "B.Fab" user "Ref Des/Assembly Bottom")
	)
	(footprint ""
		(layer "F.Cu")
		(at 46.863 -23.368 180)
		(property "Reference" "R384"
			(at 0 0 180)
			(layer "F.SilkS")
			(hide yes)
			(effects
				(font
					(size 1.27 1.27)
				)
			)
		)
		(property "Value" ""
			(at 0 0 180)
			(layer "F.Fab")
			(effects
				(font
					(size 1.27 1.27)
				)
			)
		)
		(duplicate_pad_numbers_are_jumpers no)
		(fp_line
			(start 0.7874 0.4064)
			(end -0.7874 0.4064)
			(stroke
				(width 0.1524)
				(type default)
			)
			(layer "F.SilkS")
		)
		(fp_line
			(start 0.7874 -0.4064)
			(end 0.7874 0.4064)
			(stroke
				(width 0.1524)
				(type default)
			)
			(layer "F.SilkS")
		)
		(fp_line
			(start -0.7874 0.4064)
			(end -0.7874 -0.4064)
			(stroke
				(width 0.1524)
				(type default)
			)
			(layer "F.SilkS")
		)
		(fp_line
			(start -0.7874 -0.4064)
			(end 0.7874 -0.4064)
			(stroke
				(width 0.1524)
				(type default)
			)
			(layer "F.SilkS")
		)
		(fp_line
			(start 0.67945 0.3048)
			(end 0.120396 0.3048)
			(stroke
				(width 0.1)
				(type default)
			)
			(layer "F.Fab")
		)
		(fp_line
			(start 0.67945 -0.3048)
			(end 0.67945 0.3048)
			(stroke
				(width 0.1)
				(type default)
			)
			(layer "F.Fab")
		)
		(fp_line
			(start 0.12065 -0.2794)
			(end 0.12065 -0.3048)
			(stroke
				(width 0.1)
				(type default)
			)
			(layer "F.Fab")
		)
		(fp_line
			(start 0.12065 -0.3048)
			(end 0.67945 -0.3048)
			(stroke
				(width 0.1)
				(type default)
			)
			(layer "F.Fab")
		)
		(fp_line
			(start 0.120396 0.3048)
			(end 0.120396 0.2794)
			(stroke
				(width 0.1)
				(type default)
			)
			(layer "F.Fab")
		)
		(fp_line
			(start 0.120396 0.2794)
			(end -0.12065 0.2794)
			(stroke
				(width 0.1)
				(type default)
			)
			(layer "F.Fab")
		)
		(fp_line
			(start -0.12065 0.3048)
			(end -0.67945 0.3048)
			(stroke
				(width 0.1)
				(type default)
			)
			(layer "F.Fab")
		)
		(fp_line
			(start -0.12065 0.2794)
			(end -0.12065 0.3048)
			(stroke
				(width 0.1)
				(type default)
			)
			(layer "F.Fab")
		)
		(fp_line
			(start -0.12065 -0.2794)
			(end 0.12065 -0.2794)
			(stroke
				(width 0.1)
				(type default)
			)
			(layer "F.Fab")
		)
		(fp_line
			(start -0.12065 -0.305054)
			(end -0.12065 -0.2794)
			(stroke
				(width 0.1)
				(type default)
			)
			(layer "F.Fab")
		)
		(fp_line
			(start -0.67945 0.3048)
			(end -0.67945 -0.305054)
			(stroke
				(width 0.1)
				(type default)
			)
			(layer "F.Fab")
		)
		(fp_line
			(start -0.67945 -0.305054)
			(end -0.12065 -0.305054)
			(stroke
				(width 0.1)
				(type default)
			)
			(layer "F.Fab")
		)
		(pad "1" smd circle
			(at -0.40005 0 180)
			(size 0 0)
			(layers "F.Cu" "F.Mask" "F.Paste")
			(net "USB_OC0_REAR_N")
		)
		(pad "2" smd circle
			(at 0.40005 0 180)
			(size 0 0)
			(layers "F.Cu" "F.Mask" "F.Paste")
			(net "USB_OC0_REAR_R_N")
		)
	)
	(footprint ""
		(layer "F.Cu")
		(at 24.3332 -30.6324 90)
		(property "Reference" "PR193"
			(at 0 0 90)
			(layer "F.SilkS")
			(hide yes)
			(effects
				(font
					(size 1.27 1.27)
				)
			)
		)
		(property "Value" ""
			(at 0 0 90)
			(layer "F.Fab")
			(effects
				(font
					(size 1.27 1.27)
				)
			)
		)
		(duplicate_pad_numbers_are_jumpers no)
		(fp_line
			(start 0.7874 -0.4064)
			(end 0.7874 0.4064)
			(stroke
				(width 0.1524)
				(type default)
			)
			(layer "F.SilkS")
		)
		(fp_line
			(start -0.7874 -0.4064)
			(end 0.7874 -0.4064)
			(stroke
				(width 0.1524)
				(type default)
			)
			(layer "F.SilkS")
		)
		(fp_line
			(start 0.7874 0.4064)
			(end -0.7874 0.4064)
			(stroke
				(width 0.1524)
				(type default)
			)
			(layer "F.SilkS")
		)
		(fp_line
			(start -0.7874 0.4064)
			(end -0.7874 -0.4064)
			(stroke
				(width 0.1524)
				(type default)
			)
			(layer "F.SilkS")
		)
		(fp_line
			(start -0.12065 -0.305054)
			(end -0.12065 -0.2794)
			(stroke
				(width 0.1)
				(type default)
			)
			(layer "F.Fab")
		)
		(fp_line
			(start -0.67945 -0.305054)
			(end -0.12065 -0.305054)
			(stroke
				(width 0.1)
				(type default)
			)
			(layer "F.Fab")
		)
		(fp_line
			(start 0.67945 -0.3048)
			(end 0.67945 0.3048)
			(stroke
				(width 0.1)
				(type default)
			)
			(layer "F.Fab")
		)
		(fp_line
			(start 0.12065 -0.3048)
			(end 0.67945 -0.3048)
			(stroke
				(width 0.1)
				(type default)
			)
			(layer "F.Fab")
		)
		(fp_line
			(start 0.12065 -0.2794)
			(end 0.12065 -0.3048)
			(stroke
				(width 0.1)
				(type default)
			)
			(layer "F.Fab")
		)
		(fp_line
			(start -0.12065 -0.2794)
			(end 0.12065 -0.2794)
			(stroke
				(width 0.1)
				(type default)
			)
			(layer "F.Fab")
		)
		(fp_line
			(start 0.120396 0.2794)
			(end -0.12065 0.2794)
			(stroke
				(width 0.1)
				(type default)
			)
			(layer "F.Fab")
		)
		(fp_line
			(start -0.12065 0.2794)
			(end -0.12065 0.3048)
			(stroke
				(width 0.1)
				(type default)
			)
			(layer "F.Fab")
		)
		(fp_line
			(start 0.67945 0.3048)
			(end 0.120396 0.3048)
			(stroke
				(width 0.1)
				(type default)
			)
			(layer "F.Fab")
		)
		(fp_line
			(start 0.120396 0.3048)
			(end 0.120396 0.2794)
			(stroke
				(width 0.1)
				(type default)
			)
			(layer "F.Fab")
		)
		(fp_line
			(start -0.12065 0.3048)
			(end -0.67945 0.3048)
			(stroke
				(width 0.1)
				(type default)
			)
			(layer "F.Fab")
		)
		(fp_line
			(start -0.67945 0.3048)
			(end -0.67945 -0.305054)
			(stroke
				(width 0.1)
				(type default)
			)
			(layer "F.Fab")
		)
		(pad "1" smd circle
			(at -0.40005 0 90)
			(size 0 0)
			(layers "F.Cu" "F.Mask" "F.Paste")
			(net "P3V3_AUX")
		)
		(pad "2" smd circle
			(at 0.40005 0 90)
			(size 0 0)
			(layers "F.Cu" "F.Mask" "F.Paste")
			(net "PVCC2_AUX")
		)
	)
	(footprint ""
		(layer "F.Cu")
		(at 74.74712 -35.127438)
		(property "Reference" "C124"
			(at 0 0 0)
			(layer "F.SilkS")
			(hide yes)
			(effects
				(font
					(size 1.27 1.27)
				)
			)
		)
		(property "Value" ""
			(at 0 0 0)
			(layer "F.Fab")
			(effects
				(font
					(size 1.27 1.27)
				)
			)
		)
		(duplicate_pad_numbers_are_jumpers no)
		(fp_line
			(start -1.2954 -0.5842)
			(end 1.2954 -0.5842)
			(stroke
				(width 0.1524)
				(type default)
			)
			(layer "F.SilkS")
		)
		(fp_line
			(start -1.2954 0.5842)
			(end -1.2954 -0.5842)
			(stroke
				(width 0.1524)
				(type default)
			)
			(layer "F.SilkS")
		)
		(fp_line
			(start 0 -0.5842)
			(end 0 0.5842)
			(stroke
				(width 0.1524)
				(type default)
			)
			(layer "F.SilkS")
		)
		(fp_line
			(start 1.2954 -0.5842)
			(end 1.2954 0.5842)
			(stroke
				(width 0.1524)
				(type default)
			)
			(layer "F.SilkS")
		)
		(fp_line
			(start 1.2954 0.5842)
			(end -1.2954 0.5842)
			(stroke
				(width 0.1524)
				(type default)
			)
			(layer "F.SilkS")
		)
		(fp_line
			(start -1.1938 -0.4064)
			(end -0.8636 -0.4064)
			(stroke
				(width 0.1)
				(type default)
			)
			(layer "F.Fab")
		)
		(fp_line
			(start -1.1938 0.4064)
			(end -1.1938 -0.4064)
			(stroke
				(width 0.1)
				(type default)
			)
			(layer "F.Fab")
		)
		(fp_line
			(start -0.8636 -0.4572)
			(end 0.8636 -0.4572)
			(stroke
				(width 0.1)
				(type default)
			)
			(layer "F.Fab")
		)
		(fp_line
			(start -0.8636 -0.4064)
			(end -0.8636 -0.4572)
			(stroke
				(width 0.1)
				(type default)
			)
			(layer "F.Fab")
		)
		(fp_line
			(start -0.8636 0.4064)
			(end -1.1938 0.4064)
			(stroke
				(width 0.1)
				(type default)
			)
			(layer "F.Fab")
		)
		(fp_line
			(start -0.8636 0.4572)
			(end -0.8636 0.4064)
			(stroke
				(width 0.1)
				(type default)
			)
			(layer "F.Fab")
		)
		(fp_line
			(start 0.8636 -0.4572)
			(end 0.8636 -0.4064)
			(stroke
				(width 0.1)
				(type default)
			)
			(layer "F.Fab")
		)
		(fp_line
			(start 0.8636 -0.4064)
			(end 1.1938 -0.4064)
			(stroke
				(width 0.1)
				(type default)
			)
			(layer "F.Fab")
		)
		(fp_line
			(start 0.8636 0.4064)
			(end 0.8636 0.4572)
			(stroke
				(width 0.1)
				(type default)
			)
			(layer "F.Fab")
		)
		(fp_line
			(start 0.8636 0.4572)
			(end -0.8636 0.4572)
			(stroke
				(width 0.1)
				(type default)
			)
			(layer "F.Fab")
		)
		(fp_line
			(start 1.1938 -0.4064)
			(end 1.1938 0.4064)
			(stroke
				(width 0.1)
				(type default)
			)
			(layer "F.Fab")
		)
		(fp_line
			(start 1.1938 0.4064)
			(end 0.8636 0.4064)
			(stroke
				(width 0.1)
				(type default)
			)
			(layer "F.Fab")
		)
		(pad "1" smd rect
			(at -0.7366 0 270)
			(size 0.7112 0.8128)
			(layers "F.Cu" "F.Mask" "F.Paste")
			(net "P1V8_AUX")
		)
		(pad "2" smd rect
			(at 0.7366 0 270)
			(size 0.7112 0.8128)
			(layers "F.Cu" "F.Mask" "F.Paste")
			(net "GND")
		)
	)
	(footprint ""
		(layer "F.Cu")
		(at 81.701386 -74.883264 180)
		(property "Reference" "PC253"
			(at 0 0 180)
			(layer "F.SilkS")
			(hide yes)
			(effects
				(font
					(size 1.27 1.27)
				)
			)
		)
		(property "Value" ""
			(at 0 0 180)
			(layer "F.Fab")
			(effects
				(font
					(size 1.27 1.27)
				)
			)
		)
		(duplicate_pad_numbers_are_jumpers no)
		(fp_line
			(start 0.7874 0.4064)
			(end -0.7874 0.4064)
			(stroke
				(width 0.1524)
				(type default)
			)
			(layer "F.SilkS")
		)
		(fp_line
			(start 0.7874 -0.4064)
			(end 0.7874 0.4064)
			(stroke
				(width 0.1524)
				(type default)
			)
			(layer "F.SilkS")
		)
		(fp_line
			(start -0.7874 0.4064)
			(end -0.7874 -0.4064)
			(stroke
				(width 0.1524)
				(type default)
			)
			(layer "F.SilkS")
		)
		(fp_line
			(start -0.7874 -0.4064)
			(end 0.7874 -0.4064)
			(stroke
				(width 0.1524)
				(type default)
			)
			(layer "F.SilkS")
		)
		(fp_line
			(start 0.67945 0.3048)
			(end 0.120396 0.3048)
			(stroke
				(width 0.1)
				(type default)
			)
			(layer "F.Fab")
		)
		(fp_line
			(start 0.67945 -0.3048)
			(end 0.67945 0.3048)
			(stroke
				(width 0.1)
				(type default)
			)
			(layer "F.Fab")
		)
		(fp_line
			(start 0.12065 -0.2794)
			(end 0.12065 -0.3048)
			(stroke
				(width 0.1)
				(type default)
			)
			(layer "F.Fab")
		)
		(fp_line
			(start 0.12065 -0.3048)
			(end 0.67945 -0.3048)
			(stroke
				(width 0.1)
				(type default)
			)
			(layer "F.Fab")
		)
		(fp_line
			(start 0.120396 0.3048)
			(end 0.120396 0.2794)
			(stroke
				(width 0.1)
				(type default)
			)
			(layer "F.Fab")
		)
		(fp_line
			(start 0.120396 0.2794)
			(end -0.12065 0.2794)
			(stroke
				(width 0.1)
				(type default)
			)
			(layer "F.Fab")
		)
		(fp_line
			(start -0.12065 0.3048)
			(end -0.67945 0.3048)
			(stroke
				(width 0.1)
				(type default)
			)
			(layer "F.Fab")
		)
		(fp_line
			(start -0.12065 0.2794)
			(end -0.12065 0.3048)
			(stroke
				(width 0.1)
				(type default)
			)
			(layer "F.Fab")
		)
		(fp_line
			(start -0.12065 -0.2794)
			(end 0.12065 -0.2794)
			(stroke
				(width 0.1)
				(type default)
			)
			(layer "F.Fab")
		)
		(fp_line
			(start -0.12065 -0.305054)
			(end -0.12065 -0.2794)
			(stroke
				(width 0.1)
				(type default)
			)
			(layer "F.Fab")
		)
		(fp_line
			(start -0.67945 0.3048)
			(end -0.67945 -0.305054)
			(stroke
				(width 0.1)
				(type default)
			)
			(layer "F.Fab")
		)
		(fp_line
			(start -0.67945 -0.305054)
			(end -0.12065 -0.305054)
			(stroke
				(width 0.1)
				(type default)
			)
			(layer "F.Fab")
		)
		(pad "1" smd circle
			(at -0.40005 0 180)
			(size 0 0)
			(layers "F.Cu" "F.Mask" "F.Paste")
			(net "SW_P1V2_AUX_FLT")
		)
		(pad "2" smd circle
			(at 0.40005 0 180)
			(size 0 0)
			(layers "F.Cu" "F.Mask" "F.Paste")
			(net "GND")
		)
	)
	(footprint ""
		(layer "F.Cu")
		(at 39.9542 -48.6918 180)
		(property "Reference" "R177"
			(at 0 0 180)
			(layer "F.SilkS")
			(hide yes)
			(effects
				(font
					(size 1.27 1.27)
				)
			)
		)
		(property "Value" ""
			(at 0 0 180)
			(layer "F.Fab")
			(effects
				(font
					(size 1.27 1.27)
				)
			)
		)
		(duplicate_pad_numbers_are_jumpers no)
		(fp_line
			(start 0.7874 0.4064)
			(end -0.7874 0.4064)
			(stroke
				(width 0.1524)
				(type default)
			)
			(layer "F.SilkS")
		)
		(fp_line
			(start 0.7874 -0.4064)
			(end 0.7874 0.4064)
			(stroke
				(width 0.1524)
				(type default)
			)
			(layer "F.SilkS")
		)
		(fp_line
			(start -0.7874 0.4064)
			(end -0.7874 -0.4064)
			(stroke
				(width 0.1524)
				(type default)
			)
			(layer "F.SilkS")
		)
		(fp_line
			(start -0.7874 -0.4064)
			(end 0.7874 -0.4064)
			(stroke
				(width 0.1524)
				(type default)
			)
			(layer "F.SilkS")
		)
		(fp_line
			(start 0.67945 0.3048)
			(end 0.120396 0.3048)
			(stroke
				(width 0.1)
				(type default)
			)
			(layer "F.Fab")
		)
		(fp_line
			(start 0.67945 -0.3048)
			(end 0.67945 0.3048)
			(stroke
				(width 0.1)
				(type default)
			)
			(layer "F.Fab")
		)
		(fp_line
			(start 0.12065 -0.2794)
			(end 0.12065 -0.3048)
			(stroke
				(width 0.1)
				(type default)
			)
			(layer "F.Fab")
		)
		(fp_line
			(start 0.12065 -0.3048)
			(end 0.67945 -0.3048)
			(stroke
				(width 0.1)
				(type default)
			)
			(layer "F.Fab")
		)
		(fp_line
			(start 0.120396 0.3048)
			(end 0.120396 0.2794)
			(stroke
				(width 0.1)
				(type default)
			)
			(layer "F.Fab")
		)
		(fp_line
			(start 0.120396 0.2794)
			(end -0.12065 0.2794)
			(stroke
				(width 0.1)
				(type default)
			)
			(layer "F.Fab")
		)
		(fp_line
			(start -0.12065 0.3048)
			(end -0.67945 0.3048)
			(stroke
				(width 0.1)
				(type default)
			)
			(layer "F.Fab")
		)
		(fp_line
			(start -0.12065 0.2794)
			(end -0.12065 0.3048)
			(stroke
				(width 0.1)
				(type default)
			)
			(layer "F.Fab")
		)
		(fp_line
			(start -0.12065 -0.2794)
			(end 0.12065 -0.2794)
			(stroke
				(width 0.1)
				(type default)
			)
			(layer "F.Fab")
		)
		(fp_line
			(start -0.12065 -0.305054)
			(end -0.12065 -0.2794)
			(stroke
				(width 0.1)
				(type default)
			)
			(layer "F.Fab")
		)
		(fp_line
			(start -0.67945 0.3048)
			(end -0.67945 -0.305054)
			(stroke
				(width 0.1)
				(type default)
			)
			(layer "F.Fab")
		)
		(fp_line
			(start -0.67945 -0.305054)
			(end -0.12065 -0.305054)
			(stroke
				(width 0.1)
				(type default)
			)
			(layer "F.Fab")
		)
		(pad "1" smd circle
			(at -0.40005 0 180)
			(size 0 0)
			(layers "F.Cu" "F.Mask" "F.Paste")
			(net "H_CPU1_PROCHOT_LVC1_N")
		)
		(pad "2" smd circle
			(at 0.40005 0 180)
			(size 0 0)
			(layers "F.Cu" "F.Mask" "F.Paste")
			(net "H_CPU1_PROCHOT_LVC1_R_N")
		)
	)
	(footprint ""
		(layer "F.Cu")
		(at 9.65581 -57.393332 180)
		(property "Reference" "PL19"
			(at 0 0 180)
			(layer "F.SilkS")
			(hide yes)
			(effects
				(font
					(size 1.27 1.27)
				)
			)
		)
		(property "Value" ""
			(at 0 0 180)
			(layer "F.Fab")
			(effects
				(font
					(size 1.27 1.27)
				)
			)
		)
		(duplicate_pad_numbers_are_jumpers no)
		(fp_line
			(start 1.27 0.5842)
			(end 1.27 -0.5842)
			(stroke
				(width 0.1524)
				(type default)
			)
			(layer "F.SilkS")
		)
		(fp_line
			(start 1.27 0.5842)
			(end -1.27 0.5842)
			(stroke
				(width 0.1524)
				(type default)
			)
			(layer "F.SilkS")
		)
		(fp_line
			(start 0.127 0.5842)
			(end 0.127 -0.5842)
			(stroke
				(width 0.1524)
				(type default)
			)
			(layer "F.SilkS")
		)
		(fp_line
			(start -0.127 0.5842)
			(end -0.127 -0.5842)
			(stroke
				(width 0.1524)
				(type default)
			)
			(layer "F.SilkS")
		)
		(fp_line
			(start -1.27 0.5842)
			(end -1.27 -0.5842)
			(stroke
				(width 0.1524)
				(type default)
			)
			(layer "F.SilkS")
		)
		(fp_line
			(start -1.27 -0.5588)
			(end -1.27 -0.5842)
			(stroke
				(width 0.1524)
				(type default)
			)
			(layer "F.SilkS")
		)
		(fp_line
			(start -1.27 -0.5842)
			(end 1.27 -0.5842)
			(stroke
				(width 0.1524)
				(type default)
			)
			(layer "F.SilkS")
		)
		(fp_line
			(start 1.1938 0.4064)
			(end 0.9144 0.4064)
			(stroke
				(width 0.1)
				(type default)
			)
			(layer "F.Fab")
		)
		(fp_line
			(start 1.1938 -0.406654)
			(end 1.1938 0.4064)
			(stroke
				(width 0.1)
				(type default)
			)
			(layer "F.Fab")
		)
		(fp_line
			(start 0.9144 0.508)
			(end -0.9144 0.508)
			(stroke
				(width 0.1)
				(type default)
			)
			(layer "F.Fab")
		)
		(fp_line
			(start 0.9144 0.4064)
			(end 0.9144 0.508)
			(stroke
				(width 0.1)
				(type default)
			)
			(layer "F.Fab")
		)
		(fp_line
			(start 0.9144 -0.406654)
			(end 1.1938 -0.406654)
			(stroke
				(width 0.1)
				(type default)
			)
			(layer "F.Fab")
		)
		(fp_line
			(start 0.9144 -0.508)
			(end 0.9144 -0.406654)
			(stroke
				(width 0.1)
				(type default)
			)
			(layer "F.Fab")
		)
		(fp_line
			(start -0.9144 0.508)
			(end -0.9144 0.406654)
			(stroke
				(width 0.1)
				(type default)
			)
			(layer "F.Fab")
		)
		(fp_line
			(start -0.9144 0.406654)
			(end -1.194308 0.406654)
			(stroke
				(width 0.1)
				(type default)
			)
			(layer "F.Fab")
		)
		(fp_line
			(start -0.9144 -0.406654)
			(end -0.9144 -0.508)
			(stroke
				(width 0.1)
				(type default)
			)
			(layer "F.Fab")
		)
		(fp_line
			(start -0.9144 -0.508)
			(end 0.9144 -0.508)
			(stroke
				(width 0.1)
				(type default)
			)
			(layer "F.Fab")
		)
		(fp_line
			(start -1.194308 0.406654)
			(end -1.194308 -0.406654)
			(stroke
				(width 0.1)
				(type default)
			)
			(layer "F.Fab")
		)
		(fp_line
			(start -1.194308 -0.406654)
			(end -0.9144 -0.406654)
			(stroke
				(width 0.1)
				(type default)
			)
			(layer "F.Fab")
		)
		(pad "1" smd rect
			(at -0.7366 0 90)
			(size 0.7112 0.8128)
			(layers "F.Cu" "F.Mask" "F.Paste")
			(net "P12V_AUX")
		)
		(pad "2" smd rect
			(at 0.7366 0 90)
			(size 0.7112 0.8128)
			(layers "F.Cu" "F.Mask" "F.Paste")
			(net "SW_P3V3_AUX_FLT")
		)
	)
)
